# T6G (Grand Teton) — schematic netlist excerpt (pin names and nets, part order shuffled) for the footprints in the layout excerpt that follows; sources: Cadence DE-HDL packaged netlist, KiCad conversion of 04192023_DAF0TMB3IC0_F0TG_MB_C_brd_V02_OCP.brd

J102  SCONN288_DDR506112002KQ  IO  pkg DDR288S_1-1VXC  page 104
  VIN_BULK0  = P12V_MEM_CPU1
  RFU0  = NC
  VIN_MGMT  = P3V3_AUX
  HSCL  = I3C_SPD_DDRG_CPU1_SCL
  HSDA  = I3C_SPD_DDRG_CPU1_SDA
  VSS0  = GND
  DQ0_A  = M_G_CPU1_SA_DQ<0>
  VSS1  = GND
  DQ1_A  = M_G_CPU1_SA_DQ<1>
  VSS2  = GND
  DQS0_A_T  = M_G_CPU1_SA_DQS_DP<0>
  DQS0_A_C  = M_G_CPU1_SA_DQS_DN<0>
  VSS3  = GND
  DQ4_A  = M_G_CPU1_SA_DQ<4>
  VSS4  = GND
  DQ5_A  = M_G_CPU1_SA_DQ<5>
  VSS5  = GND
  DQ8_A  = M_G_CPU1_SA_DQ<8>
  VSS6  = GND
  DQ9_A  = M_G_CPU1_SA_DQ<9>
  VSS7  = GND
  DQS1_A_T  = M_G_CPU1_SA_DQS_DP<1>
  DQS1_A_C  = M_G_CPU1_SA_DQS_DN<1>
  VSS8  = GND
  DQ12_A  = M_G_CPU1_SA_DQ<12>
  VSS9  = GND
  DQ13_A  = M_G_CPU1_SA_DQ<13>
  VSS10  = GND
  DQ16_A  = M_G_CPU1_SA_DQ<16>
  VSS11  = GND
  DQ17_A  = M_G_CPU1_SA_DQ<17>
  VSS12  = GND
  DQS2_A_T  = M_G_CPU1_SA_DQS_DP<2>
  DQS2_A_C  = M_G_CPU1_SA_DQS_DN<2>
  VSS13  = GND
  DQ20_A  = M_G_CPU1_SA_DQ<20>
  VSS14  = GND
  DQ21_A  = M_G_CPU1_SA_DQ<21>
  VSS15  = GND
  DQ24_A  = M_G_CPU1_SA_DQ<24>
  VSS16  = GND
  DQ25_A  = M_G_CPU1_SA_DQ<25>
  VSS17  = GND
  DQS3_A_T  = M_G_CPU1_SA_DQS_DP<3>
  DQS3_A_C  = M_G_CPU1_SA_DQS_DN<3>
  VSS18  = GND
  DQ28_A  = M_G_CPU1_SA_DQ<28>
  VSS19  = GND
  DQ29_A  = M_G_CPU1_SA_DQ<29>
  VSS20  = GND
  CB0_A  = M_G_CPU1_SA_CB<0>
  VSS21  = GND
  CB1_A  = M_G_CPU1_SA_CB<1>
  VSS22  = GND
  DQS4_A_T  = M_G_CPU1_SA_DQS_DP<4>
  DQS4_A_C  = M_G_CPU1_SA_DQS_DN<4>
  VSS23  = GND
  CB4_A  = M_G_CPU1_SA_CB<4>
  VSS24  = GND
  CB5_A  = M_G_CPU1_SA_CB<5>
  VSS25  = GND
  ALERT_N  = M_G_CPU1_ALERT_N
  VSS26  = GND
  CS0_A_N  = M_G_CPU1_SA_CS_N<0>
  VSS27  = GND
  CA0_A  = M_G_CPU1_SA_CA<0>
  VSS28  = GND
  CA2_A  = M_G_CPU1_SA_CA<2>
  VSS29  = GND
  CA4_A  = M_G_CPU1_SA_CA<4>
  VSS30  = GND
  CA6_A  = M_G_CPU1_SA_CA<6>
  VSS31  = GND
  PAR_A  = M_G_CPU1_SA_PAR
  VSS32  = GND
  CA0_B  = M_G_CPU1_SB_CA<0>
  VSS33  = GND
  CA2_B  = M_G_CPU1_SB_CA<2>
  VSS34  = GND
  CA4_B  = M_G_CPU1_SB_CA<4>
  VSS35  = GND
  CA6_B  = M_G_CPU1_SB_CA<6>
  VSS36  = GND
  CS0_B_N  = M_G_CPU1_SB_CS_N<0>
  VSS37  = GND
  \lbd||rsp_a_n\  = M_G_CPU1_SA_RSP<0>
  \lbs||rsp_b_n\  = M_G_CPU1_SB_RSP<0>
  VSS38  = GND
  CB4_B  = M_G_CPU1_SB_CB<4>
  VSS39  = GND
  CB5_B  = M_G_CPU1_SB_CB<5>
  VSS40  = GND
  \dqs9_b_t||tdqs9_b_t||dbi4_b_n\  = M_G_CPU1_SB_DQS_DP<9>
  \dqs9_b_c||tdqs9_b_c\  = M_G_CPU1_SB_DQS_DN<9>
  VSS41  = GND
  CB0_B  = M_G_CPU1_SB_CB<0>
  VSS42  = GND
  CB1_B  = M_G_CPU1_SB_CB<1>
  VSS43  = GND
  DQ0_B  = M_G_CPU1_SB_DQ<0>
  VSS44  = GND
  DQ1_B  = M_G_CPU1_SB_DQ<1>
  VSS45  = GND
  DQS0_B_T  = M_G_CPU1_SB_DQS_DP<0>
  DQS0_B_C  = M_G_CPU1_SB_DQS_DN<0>
  VSS46  = GND
  DQ4_B  = M_G_CPU1_SB_DQ<4>
  VSS47  = GND
  DQ5_B  = M_G_CPU1_SB_DQ<5>
  VSS48  = GND
  DQ8_B  = M_G_CPU1_SB_DQ<8>
  VSS49  = GND
  DQ9_B  = M_G_CPU1_SB_DQ<9>
  VSS50  = GND
  DQS1_B_T  = M_G_CPU1_SB_DQS_DP<1>
  DQS1_B_C  = M_G_CPU1_SB_DQS_DN<1>
  VSS51  = GND
  DQ12_B  = M_G_CPU1_SB_DQ<12>
  VSS52  = GND
  DQ13_B  = M_G_CPU1_SB_DQ<13>
  VSS53  = GND
  DQ16_B  = M_G_CPU1_SB_DQ<16>
  VSS54  = GND
  DQ17_B  = M_G_CPU1_SB_DQ<17>
  VSS55  = GND
  DQS2_B_T  = M_G_CPU1_SB_DQS_DP<2>
  DQS2_B_C  = M_G_CPU1_SB_DQS_DN<2>
  VSS56  = GND
  DQ20_B  = M_G_CPU1_SB_DQ<20>
  VSS57  = GND
  DQ21_B  = M_G_CPU1_SB_DQ<21>
  VSS58  = GND
  DQ24_B  = M_G_CPU1_SB_DQ<24>
  VSS59  = GND
  DQ25_B  = M_G_CPU1_SB_DQ<25>
  VSS60  = GND
  DQS3_B_T  = M_G_CPU1_SB_DQS_DP<3>
  DQS3_B_C  = M_G_CPU1_SB_DQS_DN<3>
  VSS61  = GND
  DQ28_B  = M_G_CPU1_SB_DQ<28>
  VSS62  = GND
  DQ29_B  = M_G_CPU1_SB_DQ<29>
  VSS63  = GND
  RFU1  = NC
  VIN_BULK1  = P12V_MEM_CPU1
  VIN_BULK2  = P12V_MEM_CPU1
  \pwr_good||fail_n\  = PWRGD_CHG_CPU1_DIMM0
  HAS  = PD_CHG_CPU1_DIMM0_SAA
  RFU2  = NC
  RFU3  = NC
  VSS64  = GND
  DQ2_A  = M_G_CPU1_SA_DQ<2>
  VSS65  = GND
  DQ3_A  = M_G_CPU1_SA_DQ<3>
  VSS66  = GND
  \dqs5_a_c||tdqs5_a_c||dqs5_a_t||tdqs5_a_t\  = M_G_CPU1_SA_DQS_DN<5>
  \dqs5_a_t||tdqs5_a_t\  = M_G_CPU1_SA_DQS_DP<5>
  VSS67  = GND
  DQ6_A  = M_G_CPU1_SA_DQ<6>
  VSS68  = GND
  DQ7_A  = M_G_CPU1_SA_DQ<7>
  VSS69  = GND
  DQ10_A  = M_G_CPU1_SA_DQ<10>
  VSS70  = GND
  DQ11_A  = M_G_CPU1_SA_DQ<11>
  VSS71  = GND
  \dqs6_a_c||tdqs6_a_c||dqs6_a_t||tdqs6_a_t\  = M_G_CPU1_SA_DQS_DN<6>
  \dqs6_a_t||tdqs6_a_t\  = M_G_CPU1_SA_DQS_DP<6>
  VSS72  = GND
  DQ14_A  = M_G_CPU1_SA_DQ<14>
  VSS73  = GND
  DQ15_A  = M_G_CPU1_SA_DQ<15>
  VSS74  = GND
  DQ18_A  = M_G_CPU1_SA_DQ<18>
  VSS75  = GND
  DQ19_A  = M_G_CPU1_SA_DQ<19>
  VSS76  = GND
  \dqs7_a_c||tdqs7_a_c\  = M_G_CPU1_SA_DQS_DN<7>
  \dqs7_a_t||tdqs7_a_t\  = M_G_CPU1_SA_DQS_DP<7>
  VSS77  = GND
  DQ22_A  = M_G_CPU1_SA_DQ<22>
  VSS78  = GND
  DQ23_A  = M_G_CPU1_SA_DQ<23>
  VSS79  = GND
  DQ26_A  = M_G_CPU1_SA_DQ<26>
  VSS80  = GND
  DQ27_A  = M_G_CPU1_SA_DQ<27>
  VSS81  = GND
  \dqs8_a_c||tdqs8_a_c\  = M_G_CPU1_SA_DQS_DN<8>
  \dqs8_a_t||tdqs8_a_t\  = M_G_CPU1_SA_DQS_DP<8>
  VSS82  = GND
  DQ30_A  = M_G_CPU1_SA_DQ<30>
  VSS83  = GND
  DQ31_A  = M_G_CPU1_SA_DQ<31>
  VSS84  = GND
  CB2_A  = M_G_CPU1_SA_CB<2>
  VSS85  = GND
  CB3_A  = M_G_CPU1_SA_CB<3>
  VSS86  = GND
  \dqs9_a_c||tdqs9_a_c\  = M_G_CPU1_SA_DQS_DN<9>
  \dqs9_a_t||tdqs9_a_t\  = M_G_CPU1_SA_DQS_DP<9>
  VSS87  = GND
  CB6_A  = M_G_CPU1_SA_CB<6>
  VSS88  = GND
  CB7_A  = M_G_CPU1_SA_CB<7>
  VSS89  = GND
  RESET_N  = M_G_CPU1_RESET_N
  VSS90  = GND
  CS1_A_N  = M_G_CPU1_SA_CS_N<1>
  VSS91  = GND
  CA1_A  = M_G_CPU1_SA_CA<1>
  VSS92  = GND
  CA3_A  = M_G_CPU1_SA_CA<3>
  VSS93  = GND
  CA5_A  = M_G_CPU1_SA_CA<5>
  VSS94  = GND
  CK_T  = M_G_CPU1_CLK_DP<0>
  CK_C  = M_G_CPU1_CLK_DN<0>
  VSS95  = GND
  RFU4  = NC
  CA1_B  = M_G_CPU1_SB_CA<1>
  VSS96  = GND
  CA3_B  = M_G_CPU1_SB_CA<3>
  VSS97  = GND
  CA5_B  = M_G_CPU1_SB_CA<5>
  VSS98  = GND
  PAR_B  = M_G_CPU1_SB_PAR
  VSS99  = GND
  CS1_B_N  = M_G_CPU1_SB_CS_N<1>
  VSS100  = GND
  RFU5  = NC
  RFU6  = NC
  VSS101  = GND
  CB6_B  = M_G_CPU1_SB_CB<6>
  VSS102  = GND
  CB7_B  = M_G_CPU1_SB_CB<7>
  VSS103  = GND
  DQS4_B_C  = M_G_CPU1_SB_DQS_DN<4>
  DQS4_B_T  = M_G_CPU1_SB_DQS_DP<4>
  VSS104  = GND
  CB2_B  = M_G_CPU1_SB_CB<2>
  VSS105  = GND
  CB3_B  = M_G_CPU1_SB_CB<3>
  VSS106  = GND
  DQ2_B  = M_G_CPU1_SB_DQ<2>
  VSS107  = GND
  DQ3_B  = M_G_CPU1_SB_DQ<3>
  VSS108  = GND
  \dqs5_b_c||tdqs5_b_c\  = M_G_CPU1_SB_DQS_DN<5>
  \dqs5_b_t||tdqs5_b_t\  = M_G_CPU1_SB_DQS_DP<5>
  VSS109  = GND
  DQ6_B  = M_G_CPU1_SB_DQ<6>
  VSS110  = GND
  DQ7_B  = M_G_CPU1_SB_DQ<7>
  VSS111  = GND
  DQ10_B  = M_G_CPU1_SB_DQ<10>
  VSS112  = GND
  DQ11_B  = M_G_CPU1_SB_DQ<11>
  VSS113  = GND
  \dqs6_b_c||tdqs6_b_c\  = M_G_CPU1_SB_DQS_DN<6>
  \dqs6_b_t||tdqs6_b_t\  = M_G_CPU1_SB_DQS_DP<6>
  VSS114  = GND
  DQ14_B  = M_G_CPU1_SB_DQ<14>
  VSS115  = GND
  DQ15_B  = M_G_CPU1_SB_DQ<15>
  VSS116  = GND
  DQ18_B  = M_G_CPU1_SB_DQ<18>
  VSS117  = GND
  DQ19_B  = M_G_CPU1_SB_DQ<19>
  VSS118  = GND
  \dqs7_b_c||tdqs7_b_c\  = M_G_CPU1_SB_DQS_DN<7>
  \dqs7_b_t||tdqs7_b_t\  = M_G_CPU1_SB_DQS_DP<7>
  VSS119  = GND
  DQ22_B  = M_G_CPU1_SB_DQ<22>
  VSS120  = GND
  DQ23_B  = M_G_CPU1_SB_DQ<23>
  VSS121  = GND
  DQ26_B  = M_G_CPU1_SB_DQ<26>
  VSS122  = GND
  DQ27_B  = M_G_CPU1_SB_DQ<27>
  VSS123  = GND
  \dqs8_b_c||tdqs8_b_c\  = M_G_CPU1_SB_DQS_DN<8>
  \dqs8_b_t||tdqs8_b_t\  = M_G_CPU1_SB_DQS_DP<8>
  VSS124  = GND
  DQ30_B  = M_G_CPU1_SB_DQ<30>
  VSS125  = GND
  DQ31_B  = M_G_CPU1_SB_DQ<31>
  VSS126  = GND
  G1  = GND
  G2  = GND
  G3  = GND

(kicad_pcb
	(version 20260206)
	(generator "pcbnew")
	(generator_version "10.0")
	(general
		(thickness 1.6)
		(legacy_teardrops no)
	)
	(paper "A4")
	(title_block
		(title "04192023_DAF0TMB3IC0_F0TG_MB_C_brd_V02_OCP.brd")
		(comment 1 "Grand Teton / footprint 4934 of 8354 (J102), pads 277-291 of 291")
	)
	(layers
		(0 "F.Cu" signal "TOP")
		(4 "In1.Cu" signal "GND")
		(6 "In2.Cu" signal "IN1")
		(8 "In3.Cu" signal "GND1")
		(10 "In4.Cu" signal "IN2")
		(12 "In5.Cu" signal "GND2")
		(14 "In6.Cu" signal "IN3")
		(16 "In7.Cu" signal "GND3")
		(18 "In8.Cu" signal "VCC")
		(20 "In9.Cu" signal "VCC1")
		(22 "In10.Cu" signal "GND4")
		(24 "In11.Cu" signal "IN4")
		(26 "In12.Cu" signal "GND5")
		(28 "In13.Cu" signal "IN5")
		(30 "In14.Cu" signal "GND6")
		(32 "In15.Cu" signal "IN6")
		(34 "In16.Cu" signal "GND7")
		(2 "B.Cu" signal "BOTTOM")
		(9 "F.Adhes" user "F.Adhesive")
		(11 "B.Adhes" user "B.Adhesive")
		(13 "F.Paste" user "Package Geometry/Pastemask Top")
		(15 "B.Paste" user "Package Geometry/Pastemask Bottom")
		(5 "F.SilkS" user "Ref Des/Silkscreen Top")
		(7 "B.SilkS" user "Ref Des/Silkscreen Bottom")
		(1 "F.Mask" user "Board Geometry/Soldermask Top")
		(3 "B.Mask" user "Board Geometry/Soldermask Bottom")
		(17 "Dwgs.User" user "User.Drawings")
		(19 "Cmts.User" user "User.Comments")
		(21 "Eco1.User" user "User.Eco1")
		(23 "Eco2.User" user "User.Eco2")
		(25 "Edge.Cuts" user "Board Geometry/Outline")
		(27 "Margin" user)
		(31 "F.CrtYd" user "Package Geometry/Place Bound Top")
		(29 "B.CrtYd" user "Package Geometry/Place Bound Bottom")
		(35 "F.Fab" user "Ref Des/Assembly Top")
		(33 "B.Fab" user "Ref Des/Assembly Bottom")
	)
	(footprint ""
		(layer "F.Cu")
		(at 166.47795 -255.560322 180)
		(property "Reference" "J102"
			(at -2.7178 -81.857088 0)
			(unlocked yes)
			(layer "F.SilkS")
			(effects
				(font
					(size 0.7874 0.5842)
					(thickness 0.1524)
				)
			)
		)
		(property "Value" ""
			(at 0 0 180)
			(layer "F.Fab")
			(effects
				(font
					(size 1.27 1.27)
				)
			)
		)
		(duplicate_pad_numbers_are_jumpers no)
		(pad "277" smd rect
			(at 2.050034 53.975 90)
			(size 0.519938 1.4986)
			(layers "F.Cu" "F.Mask" "F.Paste")
			(net "GND")
		)
		(pad "278" smd rect
			(at 2.050034 54.824884 90)
			(size 0.519938 1.4986)
			(layers "F.Cu" "F.Mask" "F.Paste")
			(net "M_G_CPU1_SB_DQ<26>")
		)
		(pad "279" smd rect
			(at 2.050034 55.675022 90)
			(size 0.519938 1.4986)
			(layers "F.Cu" "F.Mask" "F.Paste")
			(net "GND")
		)
		(pad "280" smd rect
			(at 2.050034 56.524906 90)
			(size 0.519938 1.4986)
			(layers "F.Cu" "F.Mask" "F.Paste")
			(net "M_G_CPU1_SB_DQ<27>")
		)
		(pad "281" smd rect
			(at 2.050034 57.375044 90)
			(size 0.519938 1.4986)
			(layers "F.Cu" "F.Mask" "F.Paste")
			(net "GND")
		)
		(pad "282" smd rect
			(at 2.050034 58.224928 90)
			(size 0.519938 1.4986)
			(layers "F.Cu" "F.Mask" "F.Paste")
			(net "M_G_CPU1_SB_DQS_DN<8>")
		)
		(pad "283" smd rect
			(at 2.050034 59.075066 90)
			(size 0.519938 1.4986)
			(layers "F.Cu" "F.Mask" "F.Paste")
			(net "M_G_CPU1_SB_DQS_DP<8>")
		)
		(pad "284" smd rect
			(at 2.050034 59.92495 90)
			(size 0.519938 1.4986)
			(layers "F.Cu" "F.Mask" "F.Paste")
			(net "GND")
		)
		(pad "285" smd rect
			(at 2.050034 60.775088 90)
			(size 0.519938 1.4986)
			(layers "F.Cu" "F.Mask" "F.Paste")
			(net "M_G_CPU1_SB_DQ<30>")
		)
		(pad "286" smd rect
			(at 2.050034 61.624972 90)
			(size 0.519938 1.4986)
			(layers "F.Cu" "F.Mask" "F.Paste")
			(net "GND")
		)
		(pad "287" smd rect
			(at 2.050034 62.47511 90)
			(size 0.519938 1.4986)
			(layers "F.Cu" "F.Mask" "F.Paste")
			(net "M_G_CPU1_SB_DQ<31>")
		)
		(pad "288" smd rect
			(at 2.050034 63.324994 90)
			(size 0.519938 1.4986)
			(layers "F.Cu" "F.Mask" "F.Paste")
			(net "GND")
		)
		(pad "G1" thru_hole oval
			(at 0 -68.97497 90)
			(size 1.7272 3.4798)
			(drill oval 1.2192 2.4638)
			(layers "*.Cu" "*.Mask")
			(remove_unused_layers no)
			(net "GND")
			(clearance 0.127)
			(thermal_gap 0.127)
		)
		(pad "G2" thru_hole oval
			(at 0 3.875024 90)
			(size 1.7272 3.4798)
			(drill oval 1.2192 2.4638)
			(layers "*.Cu" "*.Mask")
			(remove_unused_layers no)
			(net "GND")
			(clearance 0.127)
			(thermal_gap 0.127)
		)
		(pad "G3" thru_hole oval
			(at 0 68.97497 90)
			(size 1.7272 3.4798)
			(drill oval 1.2192 2.4638)
			(layers "*.Cu" "*.Mask")
			(remove_unused_layers no)
			(net "GND")
			(clearance 0.127)
			(thermal_gap 0.127)
		)
	)
)
